# BASEBOARD_FAB2 (Tioga Pass) — schematic netlist excerpt (pin names and nets, part order shuffled) for the footprints in the layout excerpt that follows; sources: Cadence DE-HDL packaged netlist, KiCad conversion of Wiwynn_Tioga_Pass_MB.brd

R7D37  RES  0.0 5% CHIP  pkg 0402  page 104 : A = FM_CPU1_VRM_OSC_EN ; B = FM_CPU1_VRM_322M_156M_OSC_EN

EU9R1  MOSFETN_1D3S  IC  pkg SOT5  page 200
  S1  = P12V_STBY
  S2  = P12V_STBY
  S3  = P12V_STBY
  G  = A_HSC_GATE2_R
  D  = P12V_MB0_SW

(kicad_pcb
	(version 20260206)
	(generator "pcbnew")
	(generator_version "10.0")
	(general
		(thickness 1.6)
		(legacy_teardrops no)
	)
	(paper "A4")
	(title_block
		(title "Wiwynn_Tioga_Pass_MB.brd")
		(comment 1 "Tioga Pass / footprints 4053-4054 of 4770")
	)
	(layers
		(0 "F.Cu" signal "TOP")
		(4 "In1.Cu" signal "L2GND")
		(6 "In2.Cu" signal "L3")
		(8 "In3.Cu" signal "L4GND")
		(10 "In4.Cu" signal "L5")
		(12 "In5.Cu" signal "L6GND")
		(14 "In6.Cu" signal "L7VCC")
		(16 "In7.Cu" signal "L8VCC")
		(18 "In8.Cu" signal "L9GND")
		(20 "In9.Cu" signal "L10")
		(22 "In10.Cu" signal "L11GND")
		(24 "In11.Cu" signal "L12")
		(26 "In12.Cu" signal "L13GND")
		(2 "B.Cu" signal "BOTTOM")
		(9 "F.Adhes" user "F.Adhesive")
		(11 "B.Adhes" user "B.Adhesive")
		(13 "F.Paste" user "Package Geometry/Pastemask Top")
		(15 "B.Paste" user "Package Geometry/Pastemask Bottom")
		(5 "F.SilkS" user "Ref Des/Silkscreen Top")
		(7 "B.SilkS" user "Ref Des/Silkscreen Bottom")
		(1 "F.Mask" user "Board Geometry/Soldermask Top")
		(3 "B.Mask" user "Board Geometry/Soldermask Bottom")
		(17 "Dwgs.User" user "User.Drawings")
		(19 "Cmts.User" user "User.Comments")
		(21 "Eco1.User" user "User.Eco1")
		(23 "Eco2.User" user "User.Eco2")
		(25 "Edge.Cuts" user "Board Geometry/Outline")
		(27 "Margin" user)
		(31 "F.CrtYd" user "Package Geometry/Place Bound Top")
		(29 "B.CrtYd" user "Package Geometry/Place Bound Bottom")
		(35 "F.Fab" user "Ref Des/Assembly Top")
		(33 "B.Fab" user "Ref Des/Assembly Bottom")
	)
	(footprint ""
		(layer "B.Cu")
		(at 365.506 -79.0956 -90)
		(property "Reference" "R7D37"
			(at 0 0 90)
			(layer "B.SilkS")
			(hide yes)
			(effects
				(font
					(size 1.27 1.27)
				)
				(justify mirror)
			)
		)
		(property "Value" ""
			(at 0 0 90)
			(layer "B.Fab")
			(effects
				(font
					(size 1.27 1.27)
				)
				(justify mirror)
			)
		)
		(duplicate_pad_numbers_are_jumpers no)
		(fp_poly
			(pts
				(xy 0.2794 -0.1016) (xy -0.2794 -0.1016) (xy -0.2794 0.9906) (xy 0.2794 0.9906)
			)
			(stroke
				(width 0)
				(type default)
			)
			(fill no)
			(layer "B.CrtYd")
		)
		(fp_line
			(start -0.2794 0.9906)
			(end -0.2794 -0.1016)
			(stroke
				(width 0.1)
				(type default)
			)
			(layer "B.Fab")
		)
		(fp_line
			(start 0.2794 0.9906)
			(end -0.2794 0.9906)
			(stroke
				(width 0.1)
				(type default)
			)
			(layer "B.Fab")
		)
		(fp_line
			(start -0.2794 -0.1016)
			(end 0.2794 -0.1016)
			(stroke
				(width 0.1)
				(type default)
			)
			(layer "B.Fab")
		)
		(fp_line
			(start 0.2794 -0.1016)
			(end 0.2794 0.9906)
			(stroke
				(width 0.1)
				(type default)
			)
			(layer "B.Fab")
		)
		(pad "1" smd rect
			(at 0 0 90)
			(size 0.508 0.508)
			(layers "B.Cu" "B.Mask" "B.Paste")
			(net "FM_CPU1_VRM_OSC_EN")
		)
		(pad "2" smd rect
			(at 0 0.889 90)
			(size 0.508 0.508)
			(layers "B.Cu" "B.Mask" "B.Paste")
			(net "FM_CPU1_VRM_322M_156M_OSC_EN")
		)
		(zone
			(layer "B.Cu")
			(hatch none 0.5)
			(connect_pads
				(clearance 0)
			)
			(min_thickness 0.25)
			(keepout
				(tracks not_allowed)
				(vias allowed)
				(pads allowed)
				(copperpour not_allowed)
				(footprints allowed)
			)
			(placement
				(enabled no)
				(sheetname "")
			)
			(fill
				(thermal_gap 0.5)
				(thermal_bridge_width 0.5)
				(island_removal_mode 0)
			)
			(polygon
				(pts
					(xy 364.871 -78.8416) (xy 364.871 -79.3496) (xy 365.252 -79.3496) (xy 365.252 -78.8416)
				)
			)
		)
		(zone
			(layer "B.Cu")
			(hatch none 0.5)
			(connect_pads
				(clearance 0)
			)
			(min_thickness 0.25)
			(keepout
				(tracks allowed)
				(vias not_allowed)
				(pads allowed)
				(copperpour not_allowed)
				(footprints allowed)
			)
			(placement
				(enabled no)
				(sheetname "")
			)
			(fill
				(thermal_gap 0.5)
				(thermal_bridge_width 0.5)
				(island_removal_mode 0)
			)
			(polygon
				(pts
					(xy 365.252 -78.8416) (xy 365.252 -79.3496) (xy 364.871 -79.3496) (xy 364.871 -78.8416)
				)
			)
		)
	)
	(footprint ""
		(layer "B.Cu")
		(at 21.209 -60.9092)
		(property "Reference" "EU9R1"
			(at -2.159 -1.67513 0)
			(unlocked yes)
			(layer "B.SilkS")
			(effects
				(font
					(size 0.7874 0.5842)
					(thickness 0.1524)
				)
				(justify mirror)
			)
		)
		(property "Value" ""
			(at 0 0 0)
			(layer "B.Fab")
			(effects
				(font
					(size 1.27 1.27)
				)
				(justify mirror)
			)
		)
		(duplicate_pad_numbers_are_jumpers no)
		(fp_line
			(start -4.8006 -0.7493)
			(end -4.8006 -0.635254)
			(stroke
				(width 0.1524)
				(type default)
			)
			(layer "B.SilkS")
		)
		(fp_line
			(start -4.8006 4.5593)
			(end -4.8006 4.445254)
			(stroke
				(width 0.1524)
				(type default)
			)
			(layer "B.SilkS")
		)
		(fp_line
			(start -0.4064 -0.7493)
			(end -4.8006 -0.7493)
			(stroke
				(width 0.1524)
				(type default)
			)
			(layer "B.SilkS")
		)
		(fp_line
			(start -0.4064 -0.635254)
			(end -0.4064 -0.7493)
			(stroke
				(width 0.1524)
				(type default)
			)
			(layer "B.SilkS")
		)
		(fp_line
			(start -0.4064 4.445254)
			(end -0.4064 4.5593)
			(stroke
				(width 0.1524)
				(type default)
			)
			(layer "B.SilkS")
		)
		(fp_line
			(start -0.4064 4.5593)
			(end -4.8006 4.5593)
			(stroke
				(width 0.1524)
				(type default)
			)
			(layer "B.SilkS")
		)
		(fp_circle
			(center 1.076706 -0.704342)
			(end 1.203706 -0.704342)
			(stroke
				(width 0.254)
				(type default)
			)
			(fill no)
			(layer "B.SilkS")
		)
		(fp_rect
			(start -4.8006 4.5593)
			(end -0.4064 -0.7493)
			(stroke
				(width 0)
				(type default)
			)
			(fill no)
			(layer "B.CrtYd")
		)
		(fp_line
			(start -4.8006 -0.7493)
			(end -4.8006 4.5593)
			(stroke
				(width 0.1)
				(type default)
			)
			(layer "B.Fab")
		)
		(fp_line
			(start -4.8006 4.5593)
			(end -0.4064 4.5593)
			(stroke
				(width 0.1)
				(type default)
			)
			(layer "B.Fab")
		)
		(fp_line
			(start -0.4064 -0.7493)
			(end -4.8006 -0.7493)
			(stroke
				(width 0.1)
				(type default)
			)
			(layer "B.Fab")
		)
		(fp_line
			(start -0.4064 4.5593)
			(end -0.4064 -0.7493)
			(stroke
				(width 0.1)
				(type default)
			)
			(layer "B.Fab")
		)
		(fp_circle
			(center 1.076706 -0.704342)
			(end 1.203706 -0.704342)
			(stroke
				(width 0.254)
				(type default)
			)
			(fill no)
			(layer "B.Fab")
		)
		(pad "1" smd rect
			(at 0 0 180)
			(size 1.651 0.508)
			(layers "B.Cu" "B.Mask" "B.Paste")
			(net "P12V_STBY")
		)
		(pad "2" smd rect
			(at 0 1.27 180)
			(size 1.651 0.508)
			(layers "B.Cu" "B.Mask" "B.Paste")
			(net "P12V_STBY")
		)
		(pad "3" smd rect
			(at 0 2.54 180)
			(size 1.651 0.508)
			(layers "B.Cu" "B.Mask" "B.Paste")
			(net "P12V_STBY")
		)
		(pad "4" smd rect
			(at 0 3.81 180)
			(size 1.651 0.508)
			(layers "B.Cu" "B.Mask" "B.Paste")
			(net "A_HSC_GATE2_R")
		)
		(pad "5" smd custom
			(at -3.937 1.905 180)
			(size 1.04775 1.04775)
			(layers "B.Cu" "B.Mask" "B.Paste")
			(net "P12V_MB0_SW")
			(options
				(clearance outline)
				(anchor circle)
			)
			(primitives
				(gr_poly
					(pts
						(xy -2.0955 1.651) (xy -2.0955 -1.651) (xy 0.4445 -1.651) (xy 0.4445 -2.2098) (xy 2.0955 -2.2098)
						(xy 2.0955 2.2098) (xy 0.4445 2.2098) (xy 0.4445 1.651)
					)
					(width 0)
					(fill yes)
				)
			)
		)
	)
)
